(kicad_pcb
	(version 20260206)
	(generator "pcbnew")
	(generator_version "10.0")
	(general
		(thickness 1.6)
		(legacy_teardrops no)
	)
	(paper "A4")
	(title_block
		(title "01162023_DA0F0TEBIF0_F0T_Expander_BD_F_brd_V02_OCP.brd")
		(comment 1 "Grand Teton / footprints 9608-9614 of 9728")
	)
	(layers
		(0 "F.Cu" signal "TOP")
		(4 "In1.Cu" signal "GND")
		(6 "In2.Cu" signal "VCC")
		(8 "In3.Cu" signal "VCC1")
		(10 "In4.Cu" signal "GND1")
		(12 "In5.Cu" signal "IN1")
		(14 "In6.Cu" signal "GND2")
		(16 "In7.Cu" signal "IN2")
		(18 "In8.Cu" signal "GND3")
		(20 "In9.Cu" signal "IN3")
		(22 "In10.Cu" signal "GND4")
		(24 "In11.Cu" signal "IN4")
		(26 "In12.Cu" signal "GND5")
		(28 "In13.Cu" signal "IN5")
		(30 "In14.Cu" signal "GND6")
		(32 "In15.Cu" signal "IN6")
		(34 "In16.Cu" signal "GND7")
		(2 "B.Cu" signal "BOTTOM")
		(9 "F.Adhes" user "F.Adhesive")
		(11 "B.Adhes" user "B.Adhesive")
		(13 "F.Paste" user "Package Geometry/Pastemask Top")
		(15 "B.Paste" user "Package Geometry/Pastemask Bottom")
		(5 "F.SilkS" user "Ref Des/Silkscreen Top")
		(7 "B.SilkS" user "Ref Des/Silkscreen Bottom")
		(1 "F.Mask" user "Board Geometry/Soldermask Top")
		(3 "B.Mask" user "Board Geometry/Soldermask Bottom")
		(17 "Dwgs.User" user "User.Drawings")
		(19 "Cmts.User" user "User.Comments")
		(21 "Eco1.User" user "User.Eco1")
		(23 "Eco2.User" user "User.Eco2")
		(25 "Edge.Cuts" user "Board Geometry/Outline")
		(27 "Margin" user)
		(31 "F.CrtYd" user "Package Geometry/Place Bound Top")
		(29 "B.CrtYd" user "Package Geometry/Place Bound Bottom")
		(35 "F.Fab" user "Ref Des/Assembly Top")
		(33 "B.Fab" user "Ref Des/Assembly Bottom")
	)
	(footprint ""
		(layer "B.Cu")
		(at 213.456774 -234.205526 -90)
		(property "Reference" "R6332"
			(at 0 0 90)
			(layer "B.SilkS")
			(hide yes)
			(effects
				(font
					(size 1.27 1.27)
				)
				(justify mirror)
			)
		)
		(property "Value" ""
			(at 0 0 90)
			(layer "B.Fab")
			(effects
				(font
					(size 1.27 1.27)
				)
				(justify mirror)
			)
		)
		(duplicate_pad_numbers_are_jumpers no)
		(fp_line
			(start -0.7874 0.4064)
			(end 0.7874 0.4064)
			(stroke
				(width 0.1524)
				(type default)
			)
			(layer "B.SilkS")
		)
		(fp_line
			(start 0.7874 0.4064)
			(end 0.7874 -0.4064)
			(stroke
				(width 0.1524)
				(type default)
			)
			(layer "B.SilkS")
		)
		(fp_line
			(start -0.7874 -0.4064)
			(end -0.7874 0.4064)
			(stroke
				(width 0.1524)
				(type default)
			)
			(layer "B.SilkS")
		)
		(fp_line
			(start 0.7874 -0.4064)
			(end -0.7874 -0.4064)
			(stroke
				(width 0.1524)
				(type default)
			)
			(layer "B.SilkS")
		)
		(fp_line
			(start -0.67945 0.3048)
			(end -0.120396 0.3048)
			(stroke
				(width 0.1)
				(type default)
			)
			(layer "B.Fab")
		)
		(fp_line
			(start -0.120396 0.3048)
			(end -0.120396 0.2794)
			(stroke
				(width 0.1)
				(type default)
			)
			(layer "B.Fab")
		)
		(fp_line
			(start 0.12065 0.3048)
			(end 0.67945 0.3048)
			(stroke
				(width 0.1)
				(type default)
			)
			(layer "B.Fab")
		)
		(fp_line
			(start 0.67945 0.3048)
			(end 0.67945 -0.305054)
			(stroke
				(width 0.1)
				(type default)
			)
			(layer "B.Fab")
		)
		(fp_line
			(start -0.120396 0.2794)
			(end 0.12065 0.2794)
			(stroke
				(width 0.1)
				(type default)
			)
			(layer "B.Fab")
		)
		(fp_line
			(start 0.12065 0.2794)
			(end 0.12065 0.3048)
			(stroke
				(width 0.1)
				(type default)
			)
			(layer "B.Fab")
		)
		(fp_line
			(start -0.12065 -0.2794)
			(end -0.12065 -0.3048)
			(stroke
				(width 0.1)
				(type default)
			)
			(layer "B.Fab")
		)
		(fp_line
			(start 0.12065 -0.2794)
			(end -0.12065 -0.2794)
			(stroke
				(width 0.1)
				(type default)
			)
			(layer "B.Fab")
		)
		(fp_line
			(start -0.67945 -0.3048)
			(end -0.67945 0.3048)
			(stroke
				(width 0.1)
				(type default)
			)
			(layer "B.Fab")
		)
		(fp_line
			(start -0.12065 -0.3048)
			(end -0.67945 -0.3048)
			(stroke
				(width 0.1)
				(type default)
			)
			(layer "B.Fab")
		)
		(fp_line
			(start 0.12065 -0.305054)
			(end 0.12065 -0.2794)
			(stroke
				(width 0.1)
				(type default)
			)
			(layer "B.Fab")
		)
		(fp_line
			(start 0.67945 -0.305054)
			(end 0.12065 -0.305054)
			(stroke
				(width 0.1)
				(type default)
			)
			(layer "B.Fab")
		)
		(pad "1" smd circle
			(at 0.40005 0 90)
			(size 0 0)
			(layers "B.Cu" "B.Mask" "B.Paste")
			(net "SMB_PEX3_SDA")
		)
		(pad "2" smd circle
			(at -0.40005 0 90)
			(size 0 0)
			(layers "B.Cu" "B.Mask" "B.Paste")
			(net "SMB_PEX3_MUX_SDA")
		)
	)
	(footprint ""
		(layer "B.Cu")
		(at 297.074844 -293.99992 90)
		(property "Reference" "C1640"
			(at 0 0 90)
			(layer "B.SilkS")
			(hide yes)
			(effects
				(font
					(size 1.27 1.27)
				)
				(justify mirror)
			)
		)
		(property "Value" ""
			(at 0 0 90)
			(layer "B.Fab")
			(effects
				(font
					(size 1.27 1.27)
				)
				(justify mirror)
			)
		)
		(duplicate_pad_numbers_are_jumpers no)
		(fp_line
			(start 0.299974 -0.150114)
			(end -0.299974 -0.150114)
			(stroke
				(width 0.1)
				(type default)
			)
			(layer "B.Fab")
		)
		(fp_line
			(start -0.299974 -0.150114)
			(end -0.299974 0.150114)
			(stroke
				(width 0.1)
				(type default)
			)
			(layer "B.Fab")
		)
		(fp_line
			(start 0.299974 0.150114)
			(end 0.299974 -0.150114)
			(stroke
				(width 0.1)
				(type default)
			)
			(layer "B.Fab")
		)
		(fp_line
			(start -0.299974 0.150114)
			(end 0.299974 0.150114)
			(stroke
				(width 0.1)
				(type default)
			)
			(layer "B.Fab")
		)
		(pad "1" smd rect
			(at 0.2667 0 270)
			(size 0.3048 0.381)
			(layers "B.Cu" "B.Mask" "B.Paste")
			(net "P0V8_PEX2")
		)
		(pad "2" smd rect
			(at -0.2667 0 270)
			(size 0.3048 0.381)
			(layers "B.Cu" "B.Mask" "B.Paste")
			(net "GND")
		)
	)
	(footprint ""
		(layer "B.Cu")
		(at 131.859274 -321.83451 -90)
		(property "Reference" "R6488"
			(at 0 0 90)
			(layer "B.SilkS")
			(hide yes)
			(effects
				(font
					(size 1.27 1.27)
				)
				(justify mirror)
			)
		)
		(property "Value" ""
			(at 0 0 90)
			(layer "B.Fab")
			(effects
				(font
					(size 1.27 1.27)
				)
				(justify mirror)
			)
		)
		(duplicate_pad_numbers_are_jumpers no)
		(fp_line
			(start -0.7874 0.4064)
			(end 0.7874 0.4064)
			(stroke
				(width 0.1524)
				(type default)
			)
			(layer "B.SilkS")
		)
		(fp_line
			(start 0.7874 0.4064)
			(end 0.7874 -0.4064)
			(stroke
				(width 0.1524)
				(type default)
			)
			(layer "B.SilkS")
		)
		(fp_line
			(start -0.7874 -0.4064)
			(end -0.7874 0.4064)
			(stroke
				(width 0.1524)
				(type default)
			)
			(layer "B.SilkS")
		)
		(fp_line
			(start 0.7874 -0.4064)
			(end -0.7874 -0.4064)
			(stroke
				(width 0.1524)
				(type default)
			)
			(layer "B.SilkS")
		)
		(fp_line
			(start -0.67945 0.3048)
			(end -0.120396 0.3048)
			(stroke
				(width 0.1)
				(type default)
			)
			(layer "B.Fab")
		)
		(fp_line
			(start -0.120396 0.3048)
			(end -0.120396 0.2794)
			(stroke
				(width 0.1)
				(type default)
			)
			(layer "B.Fab")
		)
		(fp_line
			(start 0.12065 0.3048)
			(end 0.67945 0.3048)
			(stroke
				(width 0.1)
				(type default)
			)
			(layer "B.Fab")
		)
		(fp_line
			(start 0.67945 0.3048)
			(end 0.67945 -0.305054)
			(stroke
				(width 0.1)
				(type default)
			)
			(layer "B.Fab")
		)
		(fp_line
			(start -0.120396 0.2794)
			(end 0.12065 0.2794)
			(stroke
				(width 0.1)
				(type default)
			)
			(layer "B.Fab")
		)
		(fp_line
			(start 0.12065 0.2794)
			(end 0.12065 0.3048)
			(stroke
				(width 0.1)
				(type default)
			)
			(layer "B.Fab")
		)
		(fp_line
			(start -0.12065 -0.2794)
			(end -0.12065 -0.3048)
			(stroke
				(width 0.1)
				(type default)
			)
			(layer "B.Fab")
		)
		(fp_line
			(start 0.12065 -0.2794)
			(end -0.12065 -0.2794)
			(stroke
				(width 0.1)
				(type default)
			)
			(layer "B.Fab")
		)
		(fp_line
			(start -0.67945 -0.3048)
			(end -0.67945 0.3048)
			(stroke
				(width 0.1)
				(type default)
			)
			(layer "B.Fab")
		)
		(fp_line
			(start -0.12065 -0.3048)
			(end -0.67945 -0.3048)
			(stroke
				(width 0.1)
				(type default)
			)
			(layer "B.Fab")
		)
		(fp_line
			(start 0.12065 -0.305054)
			(end 0.12065 -0.2794)
			(stroke
				(width 0.1)
				(type default)
			)
			(layer "B.Fab")
		)
		(fp_line
			(start 0.67945 -0.305054)
			(end 0.12065 -0.305054)
			(stroke
				(width 0.1)
				(type default)
			)
			(layer "B.Fab")
		)
		(pad "1" smd circle
			(at 0.40005 0 90)
			(size 0 0)
			(layers "B.Cu" "B.Mask" "B.Paste")
			(net "P0V8_SERDES_VDDA_PEX1")
		)
		(pad "2" smd circle
			(at -0.40005 0 90)
			(size 0 0)
			(layers "B.Cu" "B.Mask" "B.Paste")
			(net "P0V8_SERDES_VDDA_PEX1_C11")
		)
	)
	(footprint ""
		(layer "B.Cu")
		(at 449.810632 -277.073614)
		(property "Reference" "C4405"
			(at 0 0 0)
			(layer "B.SilkS")
			(hide yes)
			(effects
				(font
					(size 1.27 1.27)
				)
				(justify mirror)
			)
		)
		(property "Value" ""
			(at 0 0 0)
			(layer "B.Fab")
			(effects
				(font
					(size 1.27 1.27)
				)
				(justify mirror)
			)
		)
		(duplicate_pad_numbers_are_jumpers no)
		(fp_line
			(start -0.299974 -0.150114)
			(end -0.299974 0.150114)
			(stroke
				(width 0.1)
				(type default)
			)
			(layer "B.Fab")
		)
		(fp_line
			(start -0.299974 0.150114)
			(end 0.299974 0.150114)
			(stroke
				(width 0.1)
				(type default)
			)
			(layer "B.Fab")
		)
		(fp_line
			(start 0.299974 -0.150114)
			(end -0.299974 -0.150114)
			(stroke
				(width 0.1)
				(type default)
			)
			(layer "B.Fab")
		)
		(fp_line
			(start 0.299974 0.150114)
			(end 0.299974 -0.150114)
			(stroke
				(width 0.1)
				(type default)
			)
			(layer "B.Fab")
		)
		(pad "1" smd rect
			(at 0.2667 0 180)
			(size 0.3048 0.381)
			(layers "B.Cu" "B.Mask" "B.Paste")
			(net "P1V25_PEX3")
		)
		(pad "2" smd rect
			(at -0.2667 0 180)
			(size 0.3048 0.381)
			(layers "B.Cu" "B.Mask" "B.Paste")
			(net "GND")
		)
	)
	(footprint ""
		(layer "B.Cu")
		(at 361.407202 -275.81606 180)
		(property "Reference" "PC6619"
			(at 0 0 0)
			(layer "B.SilkS")
			(hide yes)
			(effects
				(font
					(size 1.27 1.27)
				)
				(justify mirror)
			)
		)
		(property "Value" ""
			(at 0 0 0)
			(layer "B.Fab")
			(effects
				(font
					(size 1.27 1.27)
				)
				(justify mirror)
			)
		)
		(duplicate_pad_numbers_are_jumpers no)
		(fp_line
			(start 1.524 0.762)
			(end 1.524 -0.762)
			(stroke
				(width 0.1524)
				(type default)
			)
			(layer "B.SilkS")
		)
		(fp_line
			(start 1.524 -0.762)
			(end -1.524 -0.762)
			(stroke
				(width 0.1524)
				(type default)
			)
			(layer "B.SilkS")
		)
		(fp_line
			(start -1.524 0.762)
			(end 1.524 0.762)
			(stroke
				(width 0.1524)
				(type default)
			)
			(layer "B.SilkS")
		)
		(fp_line
			(start -1.524 -0.762)
			(end -1.524 0.762)
			(stroke
				(width 0.1524)
				(type default)
			)
			(layer "B.SilkS")
		)
		(fp_line
			(start 1.1049 0.724916)
			(end -1.1049 0.724916)
			(stroke
				(width 0.1)
				(type default)
			)
			(layer "B.Fab")
		)
		(fp_line
			(start 1.1049 -0.724916)
			(end 1.1049 0.724916)
			(stroke
				(width 0.1)
				(type default)
			)
			(layer "B.Fab")
		)
		(fp_line
			(start -1.1049 0.724916)
			(end -1.1049 -0.724916)
			(stroke
				(width 0.1)
				(type default)
			)
			(layer "B.Fab")
		)
		(fp_line
			(start -1.1049 -0.724916)
			(end 1.1049 -0.724916)
			(stroke
				(width 0.1)
				(type default)
			)
			(layer "B.Fab")
		)
		(pad "1" smd rect
			(at 0.889 0 180)
			(size 1.016 1.27)
			(layers "B.Cu" "B.Mask" "B.Paste")
			(net "SW_P12V_P0V8_PEX3_FLT")
		)
		(pad "2" smd rect
			(at -0.889 0 180)
			(size 1.016 1.27)
			(layers "B.Cu" "B.Mask" "B.Paste")
			(net "GND")
		)
	)
	(footprint ""
		(layer "B.Cu")
		(at 134.735062 -321.851528 -90)
		(property "Reference" "R6479"
			(at 0 0 90)
			(layer "B.SilkS")
			(hide yes)
			(effects
				(font
					(size 1.27 1.27)
				)
				(justify mirror)
			)
		)
		(property "Value" ""
			(at 0 0 90)
			(layer "B.Fab")
			(effects
				(font
					(size 1.27 1.27)
				)
				(justify mirror)
			)
		)
		(duplicate_pad_numbers_are_jumpers no)
		(fp_line
			(start -0.7874 0.4064)
			(end 0.7874 0.4064)
			(stroke
				(width 0.1524)
				(type default)
			)
			(layer "B.SilkS")
		)
		(fp_line
			(start 0.7874 0.4064)
			(end 0.7874 -0.4064)
			(stroke
				(width 0.1524)
				(type default)
			)
			(layer "B.SilkS")
		)
		(fp_line
			(start -0.7874 -0.4064)
			(end -0.7874 0.4064)
			(stroke
				(width 0.1524)
				(type default)
			)
			(layer "B.SilkS")
		)
		(fp_line
			(start 0.7874 -0.4064)
			(end -0.7874 -0.4064)
			(stroke
				(width 0.1524)
				(type default)
			)
			(layer "B.SilkS")
		)
		(fp_line
			(start -0.67945 0.3048)
			(end -0.120396 0.3048)
			(stroke
				(width 0.1)
				(type default)
			)
			(layer "B.Fab")
		)
		(fp_line
			(start -0.120396 0.3048)
			(end -0.120396 0.2794)
			(stroke
				(width 0.1)
				(type default)
			)
			(layer "B.Fab")
		)
		(fp_line
			(start 0.12065 0.3048)
			(end 0.67945 0.3048)
			(stroke
				(width 0.1)
				(type default)
			)
			(layer "B.Fab")
		)
		(fp_line
			(start 0.67945 0.3048)
			(end 0.67945 -0.305054)
			(stroke
				(width 0.1)
				(type default)
			)
			(layer "B.Fab")
		)
		(fp_line
			(start -0.120396 0.2794)
			(end 0.12065 0.2794)
			(stroke
				(width 0.1)
				(type default)
			)
			(layer "B.Fab")
		)
		(fp_line
			(start 0.12065 0.2794)
			(end 0.12065 0.3048)
			(stroke
				(width 0.1)
				(type default)
			)
			(layer "B.Fab")
		)
		(fp_line
			(start -0.12065 -0.2794)
			(end -0.12065 -0.3048)
			(stroke
				(width 0.1)
				(type default)
			)
			(layer "B.Fab")
		)
		(fp_line
			(start 0.12065 -0.2794)
			(end -0.12065 -0.2794)
			(stroke
				(width 0.1)
				(type default)
			)
			(layer "B.Fab")
		)
		(fp_line
			(start -0.67945 -0.3048)
			(end -0.67945 0.3048)
			(stroke
				(width 0.1)
				(type default)
			)
			(layer "B.Fab")
		)
		(fp_line
			(start -0.12065 -0.3048)
			(end -0.67945 -0.3048)
			(stroke
				(width 0.1)
				(type default)
			)
			(layer "B.Fab")
		)
		(fp_line
			(start 0.12065 -0.305054)
			(end 0.12065 -0.2794)
			(stroke
				(width 0.1)
				(type default)
			)
			(layer "B.Fab")
		)
		(fp_line
			(start 0.67945 -0.305054)
			(end 0.12065 -0.305054)
			(stroke
				(width 0.1)
				(type default)
			)
			(layer "B.Fab")
		)
		(pad "1" smd circle
			(at 0.40005 0 90)
			(size 0 0)
			(layers "B.Cu" "B.Mask" "B.Paste")
			(net "P0V8_SERDES_VDDA_PEX1")
		)
		(pad "2" smd circle
			(at -0.40005 0 90)
			(size 0 0)
			(layers "B.Cu" "B.Mask" "B.Paste")
			(net "P0V8_SERDES_VDDA_PEX1_C4")
		)
	)
	(footprint ""
		(layer "B.Cu")
		(at 397.166084 -138.421618 180)
		(property "Reference" "R309"
			(at 0 0 0)
			(layer "B.SilkS")
			(hide yes)
			(effects
				(font
					(size 1.27 1.27)
				)
				(justify mirror)
			)
		)
		(property "Value" ""
			(at 0 0 0)
			(layer "B.Fab")
			(effects
				(font
					(size 1.27 1.27)
				)
				(justify mirror)
			)
		)
		(duplicate_pad_numbers_are_jumpers no)
		(fp_line
			(start 0.7874 0.4064)
			(end 0.7874 -0.4064)
			(stroke
				(width 0.1524)
				(type default)
			)
			(layer "B.SilkS")
		)
		(fp_line
			(start 0.7874 -0.4064)
			(end -0.7874 -0.4064)
			(stroke
				(width 0.1524)
				(type default)
			)
			(layer "B.SilkS")
		)
		(fp_line
			(start -0.7874 0.4064)
			(end 0.7874 0.4064)
			(stroke
				(width 0.1524)
				(type default)
			)
			(layer "B.SilkS")
		)
		(fp_line
			(start -0.7874 -0.4064)
			(end -0.7874 0.4064)
			(stroke
				(width 0.1524)
				(type default)
			)
			(layer "B.SilkS")
		)
		(fp_line
			(start 0.67945 0.3048)
			(end 0.67945 -0.305054)
			(stroke
				(width 0.1)
				(type default)
			)
			(layer "B.Fab")
		)
		(fp_line
			(start 0.67945 -0.305054)
			(end 0.12065 -0.305054)
			(stroke
				(width 0.1)
				(type default)
			)
			(layer "B.Fab")
		)
		(fp_line
			(start 0.12065 0.3048)
			(end 0.67945 0.3048)
			(stroke
				(width 0.1)
				(type default)
			)
			(layer "B.Fab")
		)
		(fp_line
			(start 0.12065 0.2794)
			(end 0.12065 0.3048)
			(stroke
				(width 0.1)
				(type default)
			)
			(layer "B.Fab")
		)
		(fp_line
			(start 0.12065 -0.2794)
			(end -0.12065 -0.2794)
			(stroke
				(width 0.1)
				(type default)
			)
			(layer "B.Fab")
		)
		(fp_line
			(start 0.12065 -0.305054)
			(end 0.12065 -0.2794)
			(stroke
				(width 0.1)
				(type default)
			)
			(layer "B.Fab")
		)
		(fp_line
			(start -0.120396 0.3048)
			(end -0.120396 0.2794)
			(stroke
				(width 0.1)
				(type default)
			)
			(layer "B.Fab")
		)
		(fp_line
			(start -0.120396 0.2794)
			(end 0.12065 0.2794)
			(stroke
				(width 0.1)
				(type default)
			)
			(layer "B.Fab")
		)
		(fp_line
			(start -0.12065 -0.2794)
			(end -0.12065 -0.3048)
			(stroke
				(width 0.1)
				(type default)
			)
			(layer "B.Fab")
		)
		(fp_line
			(start -0.12065 -0.3048)
			(end -0.67945 -0.3048)
			(stroke
				(width 0.1)
				(type default)
			)
			(layer "B.Fab")
		)
		(fp_line
			(start -0.67945 0.3048)
			(end -0.120396 0.3048)
			(stroke
				(width 0.1)
				(type default)
			)
			(layer "B.Fab")
		)
		(fp_line
			(start -0.67945 -0.3048)
			(end -0.67945 0.3048)
			(stroke
				(width 0.1)
				(type default)
			)
			(layer "B.Fab")
		)
		(pad "1" smd circle
			(at 0.40005 0)
			(size 0 0)
			(layers "B.Cu" "B.Mask" "B.Paste")
			(net "NIC6_AUX_PWR_EN_R")
		)
		(pad "2" smd circle
			(at -0.40005 0)
			(size 0 0)
			(layers "B.Cu" "B.Mask" "B.Paste")
			(net "NIC6_AUX_PWR_EN")
		)
	)
)
